(kicad_pcb
	(version 20260206)
	(generator "pcbnew")
	(generator_version "10.0")
	(general
		(thickness 1.6)
		(legacy_teardrops no)
	)
	(paper "A4")
	(title_block
		(title "baseboard — 13948-1b.1110WZS1818.brd")
		(comment 1 "Honey Badger (Wiwynn) / footprints 1036-1042 of 2523")
	)
	(layers
		(0 "F.Cu" signal "TOP")
		(4 "In1.Cu" signal "L2GND")
		(6 "In2.Cu" signal "L3")
		(8 "In3.Cu" signal "L4VCC")
		(10 "In4.Cu" signal "L5VCC")
		(12 "In5.Cu" signal "L6")
		(14 "In6.Cu" signal "L7GND")
		(2 "B.Cu" signal "BOTTOM")
		(9 "F.Adhes" user "F.Adhesive")
		(11 "B.Adhes" user "B.Adhesive")
		(13 "F.Paste" user "Package Geometry/Pastemask Top")
		(15 "B.Paste" user "Package Geometry/Pastemask Bottom")
		(5 "F.SilkS" user "Ref Des/Silkscreen Top")
		(7 "B.SilkS" user "Ref Des/Silkscreen Bottom")
		(1 "F.Mask" user "Board Geometry/Soldermask Top")
		(3 "B.Mask" user "Board Geometry/Soldermask Bottom")
		(17 "Dwgs.User" user "User.Drawings")
		(19 "Cmts.User" user "User.Comments")
		(21 "Eco1.User" user "User.Eco1")
		(23 "Eco2.User" user "User.Eco2")
		(25 "Edge.Cuts" user "Board Geometry/Outline")
		(27 "Margin" user)
		(31 "F.CrtYd" user "Package Geometry/Place Bound Top")
		(29 "B.CrtYd" user "Package Geometry/Place Bound Bottom")
		(35 "F.Fab" user "Ref Des/Assembly Top")
		(33 "B.Fab" user "Ref Des/Assembly Bottom")
	)
	(footprint ""
		(layer "F.Cu")
		(at 174.51197 -67.183)
		(property "Reference" "C293"
			(at 0 0 0)
			(layer "F.SilkS")
			(hide yes)
			(effects
				(font
					(size 1.27 1.27)
				)
			)
		)
		(property "Value" "SCD1U25V2KX-2-GP"
			(at 1.1811 -2.7051 0)
			(unlocked yes)
			(layer "F.Fab")
			(hide yes)
			(effects
				(font
					(size 1.016 1.016)
					(thickness 0.1524)
				)
			)
		)
		(property "Device Type" "C402H22"
			(at 1.1811 -4.2291 0)
			(unlocked yes)
			(layer "F.Fab")
			(hide yes)
			(effects
				(font
					(size 1.016 1.016)
					(thickness 0.1524)
				)
			)
		)
		(duplicate_pad_numbers_are_jumpers no)
		(fp_rect
			(start -0.4318 0.9525)
			(end 0.4318 -0.9525)
			(stroke
				(width 0)
				(type default)
			)
			(fill no)
			(layer "F.CrtYd")
		)
		(fp_rect
			(start -0.4318 0.9525)
			(end 0.4318 -0.9525)
			(stroke
				(width 0)
				(type default)
			)
			(fill no)
			(layer "F.Fab")
		)
		(pad "1" smd custom
			(at 0 -0.4445)
			(size 0.1524 0.1524)
			(layers "F.Cu" "F.Mask" "F.Paste")
			(net "TP_MSB_A45_GBE_RX_P")
			(options
				(clearance outline)
				(anchor circle)
			)
			(primitives
				(gr_poly
					(pts
						(arc
							(start 0.3048 -0.2032)
							(mid 0.275042 -0.275042)
							(end 0.2032 -0.3048)
						)
						(arc
							(start -0.2032 -0.3048)
							(mid -0.275042 -0.275042)
							(end -0.3048 -0.2032)
						)
						(arc
							(start -0.3048 0.2032)
							(mid -0.275042 0.275042)
							(end -0.2032 0.3048)
						)
						(arc
							(start 0.2032 0.3048)
							(mid 0.275042 0.275042)
							(end 0.3048 0.2032)
						)
					)
					(width 0)
					(fill yes)
				)
			)
		)
		(pad "2" smd custom
			(at 0 0.4445)
			(size 0.1524 0.1524)
			(layers "F.Cu" "F.Mask" "F.Paste")
			(net "GND")
			(options
				(clearance outline)
				(anchor circle)
			)
			(primitives
				(gr_poly
					(pts
						(arc
							(start 0.3048 -0.2032)
							(mid 0.275042 -0.275042)
							(end 0.2032 -0.3048)
						)
						(arc
							(start -0.2032 -0.3048)
							(mid -0.275042 -0.275042)
							(end -0.3048 -0.2032)
						)
						(arc
							(start -0.3048 0.2032)
							(mid -0.275042 0.275042)
							(end -0.2032 0.3048)
						)
						(arc
							(start 0.2032 0.3048)
							(mid 0.275042 0.275042)
							(end 0.3048 0.2032)
						)
					)
					(width 0)
					(fill yes)
				)
			)
		)
	)
	(footprint ""
		(layer "F.Cu")
		(at 196.538596 -120.669812 -90)
		(property "Reference" "PC230"
			(at 0 0 270)
			(layer "F.SilkS")
			(hide yes)
			(effects
				(font
					(size 1.27 1.27)
				)
			)
		)
		(property "Value" "SC3300P50V2KX-1GP"
			(at 1.1811 -2.7051 270)
			(unlocked yes)
			(layer "F.Fab")
			(hide yes)
			(effects
				(font
					(size 1.016 1.016)
					(thickness 0.1524)
				)
			)
		)
		(property "Device Type" "C402H22"
			(at 1.1811 -4.2291 270)
			(unlocked yes)
			(layer "F.Fab")
			(hide yes)
			(effects
				(font
					(size 1.016 1.016)
					(thickness 0.1524)
				)
			)
		)
		(duplicate_pad_numbers_are_jumpers no)
		(fp_rect
			(start -0.4318 0.9525)
			(end 0.4318 -0.9525)
			(stroke
				(width 0)
				(type default)
			)
			(fill no)
			(layer "F.CrtYd")
		)
		(fp_rect
			(start -0.4318 0.9525)
			(end 0.4318 -0.9525)
			(stroke
				(width 0)
				(type default)
			)
			(fill no)
			(layer "F.Fab")
		)
		(pad "1" smd custom
			(at 0 -0.4445 270)
			(size 0.1524 0.1524)
			(layers "F.Cu" "F.Mask" "F.Paste")
			(net "P1V5_E_SS")
			(options
				(clearance outline)
				(anchor circle)
			)
			(primitives
				(gr_poly
					(pts
						(arc
							(start 0.3048 -0.2032)
							(mid 0.275042 -0.275042)
							(end 0.2032 -0.3048)
						)
						(arc
							(start -0.2032 -0.3048)
							(mid -0.275042 -0.275042)
							(end -0.3048 -0.2032)
						)
						(arc
							(start -0.3048 0.2032)
							(mid -0.275042 0.275042)
							(end -0.2032 0.3048)
						)
						(arc
							(start 0.2032 0.3048)
							(mid 0.275042 0.275042)
							(end 0.3048 0.2032)
						)
					)
					(width 0)
					(fill yes)
				)
			)
		)
		(pad "2" smd custom
			(at 0 0.4445 270)
			(size 0.1524 0.1524)
			(layers "F.Cu" "F.Mask" "F.Paste")
			(net "AGND_P1V5_E")
			(options
				(clearance outline)
				(anchor circle)
			)
			(primitives
				(gr_poly
					(pts
						(arc
							(start 0.3048 -0.2032)
							(mid 0.275042 -0.275042)
							(end 0.2032 -0.3048)
						)
						(arc
							(start -0.2032 -0.3048)
							(mid -0.275042 -0.275042)
							(end -0.3048 -0.2032)
						)
						(arc
							(start -0.3048 0.2032)
							(mid -0.275042 0.275042)
							(end -0.2032 0.3048)
						)
						(arc
							(start 0.2032 0.3048)
							(mid 0.275042 0.275042)
							(end 0.3048 0.2032)
						)
					)
					(width 0)
					(fill yes)
				)
			)
		)
	)
	(footprint ""
		(layer "F.Cu")
		(at 334.391 -211.455 180)
		(property "Reference" "R212"
			(at 0 0 180)
			(layer "F.SilkS")
			(hide yes)
			(effects
				(font
					(size 1.27 1.27)
				)
			)
		)
		(property "Value" "0R2J-2-GP"
			(at 0.064008 -3.993896 180)
			(unlocked yes)
			(layer "F.Fab")
			(hide yes)
			(effects
				(font
					(size 1.016 1.016)
					(thickness 0.1524)
				)
			)
		)
		(property "Device Type" "R402H16"
			(at 0.064008 -5.517896 180)
			(unlocked yes)
			(layer "F.Fab")
			(hide yes)
			(effects
				(font
					(size 1.016 1.016)
					(thickness 0.1524)
				)
			)
		)
		(duplicate_pad_numbers_are_jumpers no)
		(fp_line
			(start 0.508 -0.9398)
			(end -0.508 -0.9398)
			(stroke
				(width 0.1524)
				(type default)
			)
			(layer "F.SilkS")
		)
		(fp_line
			(start -0.508 -0.9398)
			(end -0.508 0.9398)
			(stroke
				(width 0.1524)
				(type default)
			)
			(layer "F.SilkS")
		)
		(fp_rect
			(start -0.508 0.9398)
			(end 0.508 -0.9398)
			(stroke
				(width 0)
				(type default)
			)
			(fill no)
			(layer "F.CrtYd")
		)
		(fp_rect
			(start -0.508 0.9398)
			(end 0.508 -0.9398)
			(stroke
				(width 0)
				(type default)
			)
			(fill no)
			(layer "F.Fab")
		)
		(pad "1" smd custom
			(at 0 -0.4445 180)
			(size 0.1397 0.1397)
			(layers "F.Cu" "F.Mask" "F.Paste")
			(net "EEPROM_SDA")
			(options
				(clearance outline)
				(anchor circle)
			)
			(primitives
				(gr_poly
					(pts
						(arc
							(start -0.1778 -0.2794)
							(mid -0.249642 -0.249642)
							(end -0.2794 -0.1778)
						)
						(arc
							(start -0.2794 0.1778)
							(mid -0.249642 0.249642)
							(end -0.1778 0.2794)
						)
						(arc
							(start 0.1778 0.2794)
							(mid 0.249642 0.249642)
							(end 0.2794 0.1778)
						)
						(arc
							(start 0.2794 -0.1778)
							(mid 0.249642 -0.249642)
							(end 0.1778 -0.2794)
						)
					)
					(width 0)
					(fill yes)
				)
			)
		)
		(pad "2" smd custom
			(at 0 0.4445 180)
			(size 0.1397 0.1397)
			(layers "F.Cu" "F.Mask" "F.Paste")
			(net "BMC_I2C_A_SDA")
			(options
				(clearance outline)
				(anchor circle)
			)
			(primitives
				(gr_poly
					(pts
						(arc
							(start -0.1778 -0.2794)
							(mid -0.249642 -0.249642)
							(end -0.2794 -0.1778)
						)
						(arc
							(start -0.2794 0.1778)
							(mid -0.249642 0.249642)
							(end -0.1778 0.2794)
						)
						(arc
							(start 0.1778 0.2794)
							(mid 0.249642 0.249642)
							(end 0.2794 0.1778)
						)
						(arc
							(start 0.2794 -0.1778)
							(mid 0.249642 -0.249642)
							(end 0.1778 -0.2794)
						)
					)
					(width 0)
					(fill yes)
				)
			)
		)
	)
	(footprint ""
		(layer "F.Cu")
		(at 92.21597 -95.504 -90)
		(property "Reference" "SR779"
			(at 0 0 270)
			(layer "F.SilkS")
			(hide yes)
			(effects
				(font
					(size 1.27 1.27)
				)
			)
		)
		(property "Value" "4K7R2F-GP"
			(at 0.064008 -3.993896 270)
			(unlocked yes)
			(layer "F.Fab")
			(hide yes)
			(effects
				(font
					(size 1.016 1.016)
					(thickness 0.1524)
				)
			)
		)
		(property "Device Type" "R402H16"
			(at 0.064008 -5.517896 270)
			(unlocked yes)
			(layer "F.Fab")
			(hide yes)
			(effects
				(font
					(size 1.016 1.016)
					(thickness 0.1524)
				)
			)
		)
		(duplicate_pad_numbers_are_jumpers no)
		(fp_line
			(start -0.508 -0.9398)
			(end -0.508 0.9398)
			(stroke
				(width 0.1524)
				(type default)
			)
			(layer "F.SilkS")
		)
		(fp_line
			(start 0.508 -0.9398)
			(end -0.508 -0.9398)
			(stroke
				(width 0.1524)
				(type default)
			)
			(layer "F.SilkS")
		)
		(fp_rect
			(start -0.508 0.9398)
			(end 0.508 -0.9398)
			(stroke
				(width 0)
				(type default)
			)
			(fill no)
			(layer "F.CrtYd")
		)
		(fp_rect
			(start -0.508 0.9398)
			(end 0.508 -0.9398)
			(stroke
				(width 0)
				(type default)
			)
			(fill no)
			(layer "F.Fab")
		)
		(pad "1" smd custom
			(at 0 -0.4445 270)
			(size 0.1397 0.1397)
			(layers "F.Cu" "F.Mask" "F.Paste")
			(net "EXP_XM_ADDR_18")
			(options
				(clearance outline)
				(anchor circle)
			)
			(primitives
				(gr_poly
					(pts
						(arc
							(start -0.1778 -0.2794)
							(mid -0.249642 -0.249642)
							(end -0.2794 -0.1778)
						)
						(arc
							(start -0.2794 0.1778)
							(mid -0.249642 0.249642)
							(end -0.1778 0.2794)
						)
						(arc
							(start 0.1778 0.2794)
							(mid 0.249642 0.249642)
							(end 0.2794 0.1778)
						)
						(arc
							(start 0.2794 -0.1778)
							(mid 0.249642 -0.249642)
							(end 0.1778 -0.2794)
						)
					)
					(width 0)
					(fill yes)
				)
			)
		)
		(pad "2" smd custom
			(at 0 0.4445 270)
			(size 0.1397 0.1397)
			(layers "F.Cu" "F.Mask" "F.Paste")
			(net "GND")
			(options
				(clearance outline)
				(anchor circle)
			)
			(primitives
				(gr_poly
					(pts
						(arc
							(start -0.1778 -0.2794)
							(mid -0.249642 -0.249642)
							(end -0.2794 -0.1778)
						)
						(arc
							(start -0.2794 0.1778)
							(mid -0.249642 0.249642)
							(end -0.1778 0.2794)
						)
						(arc
							(start 0.1778 0.2794)
							(mid 0.249642 0.249642)
							(end 0.2794 0.1778)
						)
						(arc
							(start 0.2794 -0.1778)
							(mid 0.249642 -0.249642)
							(end 0.1778 -0.2794)
						)
					)
					(width 0)
					(fill yes)
				)
			)
		)
	)
	(footprint ""
		(layer "F.Cu")
		(at 280.289 -197.231 -90)
		(property "Reference" "C195"
			(at 0 0 270)
			(layer "F.SilkS")
			(hide yes)
			(effects
				(font
					(size 1.27 1.27)
				)
			)
		)
		(property "Value" "SCD1U16V2KX-3GP"
			(at 1.1811 -2.7051 270)
			(unlocked yes)
			(layer "F.Fab")
			(hide yes)
			(effects
				(font
					(size 1.016 1.016)
					(thickness 0.1524)
				)
			)
		)
		(property "Device Type" "C402H22"
			(at 1.1811 -4.2291 270)
			(unlocked yes)
			(layer "F.Fab")
			(hide yes)
			(effects
				(font
					(size 1.016 1.016)
					(thickness 0.1524)
				)
			)
		)
		(duplicate_pad_numbers_are_jumpers no)
		(fp_rect
			(start -0.4318 0.9525)
			(end 0.4318 -0.9525)
			(stroke
				(width 0)
				(type default)
			)
			(fill no)
			(layer "F.CrtYd")
		)
		(fp_rect
			(start -0.4318 0.9525)
			(end 0.4318 -0.9525)
			(stroke
				(width 0)
				(type default)
			)
			(fill no)
			(layer "F.Fab")
		)
		(pad "1" smd custom
			(at 0 -0.4445 270)
			(size 0.1524 0.1524)
			(layers "F.Cu" "F.Mask" "F.Paste")
			(net "MPLLAV33")
			(options
				(clearance outline)
				(anchor circle)
			)
			(primitives
				(gr_poly
					(pts
						(arc
							(start 0.3048 -0.2032)
							(mid 0.275042 -0.275042)
							(end 0.2032 -0.3048)
						)
						(arc
							(start -0.2032 -0.3048)
							(mid -0.275042 -0.275042)
							(end -0.3048 -0.2032)
						)
						(arc
							(start -0.3048 0.2032)
							(mid -0.275042 0.275042)
							(end -0.2032 0.3048)
						)
						(arc
							(start 0.2032 0.3048)
							(mid 0.275042 0.275042)
							(end 0.3048 0.2032)
						)
					)
					(width 0)
					(fill yes)
				)
			)
		)
		(pad "2" smd custom
			(at 0 0.4445 270)
			(size 0.1524 0.1524)
			(layers "F.Cu" "F.Mask" "F.Paste")
			(net "GND")
			(options
				(clearance outline)
				(anchor circle)
			)
			(primitives
				(gr_poly
					(pts
						(arc
							(start 0.3048 -0.2032)
							(mid 0.275042 -0.275042)
							(end 0.2032 -0.3048)
						)
						(arc
							(start -0.2032 -0.3048)
							(mid -0.275042 -0.275042)
							(end -0.3048 -0.2032)
						)
						(arc
							(start -0.3048 0.2032)
							(mid -0.275042 0.275042)
							(end -0.2032 0.3048)
						)
						(arc
							(start 0.2032 0.3048)
							(mid 0.275042 0.275042)
							(end 0.3048 0.2032)
						)
					)
					(width 0)
					(fill yes)
				)
			)
		)
	)
	(footprint ""
		(layer "F.Cu")
		(at 185.42 -146.558 90)
		(property "Reference" "SU78"
			(at 0 0 90)
			(layer "F.SilkS")
			(hide yes)
			(effects
				(font
					(size 1.27 1.27)
				)
			)
		)
		(property "Value" "PCA9306DCTT-GP"
			(at 0 -11.6332 90)
			(unlocked yes)
			(layer "F.Fab")
			(hide yes)
			(effects
				(font
					(size 1.016 1.016)
					(thickness 0.1524)
				)
			)
		)
		(property "Device Type" "SSOIC8H52"
			(at 0 -13.1572 90)
			(unlocked yes)
			(layer "F.Fab")
			(hide yes)
			(effects
				(font
					(size 1.016 1.016)
					(thickness 0.1524)
				)
			)
		)
		(duplicate_pad_numbers_are_jumpers no)
		(fp_line
			(start 1.0668 -0.5842)
			(end 1.0668 0.5842)
			(stroke
				(width 0.1524)
				(type default)
			)
			(layer "F.SilkS")
		)
		(fp_line
			(start -1.7018 -0.5842)
			(end 1.0668 -0.5842)
			(stroke
				(width 0.1524)
				(type default)
			)
			(layer "F.SilkS")
		)
		(fp_line
			(start -1.7018 -0.5842)
			(end -1.7018 2.286)
			(stroke
				(width 0.1524)
				(type default)
			)
			(layer "F.SilkS")
		)
		(fp_line
			(start -1.397 0)
			(end -1.7018 -0.3048)
			(stroke
				(width 0.1524)
				(type default)
			)
			(layer "F.SilkS")
		)
		(fp_line
			(start -1.397 0)
			(end -1.7018 0.3048)
			(stroke
				(width 0.1524)
				(type default)
			)
			(layer "F.SilkS")
		)
		(fp_line
			(start 1.0668 0.5842)
			(end -1.524 0.5842)
			(stroke
				(width 0.1524)
				(type default)
			)
			(layer "F.SilkS")
		)
		(fp_line
			(start -1.524 0.5842)
			(end -1.524 2.286)
			(stroke
				(width 0.508)
				(type default)
			)
			(layer "F.SilkS")
		)
		(fp_poly
			(pts
				(xy -1.1684 -0.5842) (xy 1.0668 -0.5842) (xy 1.0668 0.5842) (xy -1.1684 0.5842)
			)
			(stroke
				(width 0)
				(type default)
			)
			(fill yes)
			(layer "F.SilkS")
		)
		(fp_poly
			(pts
				(xy -1.778 2.54) (xy 1.778 2.54) (xy 1.778 -2.54) (xy -1.778 -2.54)
			)
			(stroke
				(width 0)
				(type default)
			)
			(fill no)
			(layer "F.CrtYd")
		)
		(fp_poly
			(pts
				(xy -1.778 -2.54) (xy 1.778 -2.54) (xy 1.778 2.54) (xy -1.778 2.54)
			)
			(stroke
				(width 0)
				(type default)
			)
			(fill no)
			(layer "F.Fab")
		)
		(pad "1" smd rect
			(at -0.97536 1.6256 90)
			(size 0.3556 1.524)
			(layers "F.Cu" "F.Mask" "F.Paste")
			(net "GND")
		)
		(pad "2" smd rect
			(at -0.32512 1.6256 90)
			(size 0.3556 1.524)
			(layers "F.Cu" "F.Mask" "F.Paste")
			(net "P1V8_E")
		)
		(pad "3" smd rect
			(at 0.32512 1.6256 90)
			(size 0.3556 1.524)
			(layers "F.Cu" "F.Mask" "F.Paste")
			(net "EXP_I2C_SCL_4")
		)
		(pad "4" smd rect
			(at 0.97536 1.6256 90)
			(size 0.3556 1.524)
			(layers "F.Cu" "F.Mask" "F.Paste")
			(net "EXP_I2C_SDA_4")
		)
		(pad "5" smd rect
			(at 0.97536 -1.6256 90)
			(size 0.3556 1.524)
			(layers "F.Cu" "F.Mask" "F.Paste")
			(net "BMC_I2C_C_SDA")
		)
		(pad "6" smd rect
			(at 0.32512 -1.6256 90)
			(size 0.3556 1.524)
			(layers "F.Cu" "F.Mask" "F.Paste")
			(net "BMC_I2C_C_SCL")
		)
		(pad "7" smd rect
			(at -0.32512 -1.6256 90)
			(size 0.3556 1.524)
			(layers "F.Cu" "F.Mask" "F.Paste")
			(net "EXP_I2C_VREF_3")
		)
		(pad "8" smd rect
			(at -0.97536 -1.6256 90)
			(size 0.3556 1.524)
			(layers "F.Cu" "F.Mask" "F.Paste")
			(net "EXP_I2C_VREF_3")
		)
	)
	(footprint ""
		(layer "F.Cu")
		(at 332.105 -96.52 90)
		(property "Reference" "PC38"
			(at 0 0 90)
			(layer "F.SilkS")
			(hide yes)
			(effects
				(font
					(size 1.27 1.27)
				)
			)
		)
		(property "Value" "SC100U6D3V6MX-GP"
			(at -0.0762 -5.1308 90)
			(unlocked yes)
			(layer "F.Fab")
			(hide yes)
			(effects
				(font
					(size 1.016 1.016)
					(thickness 0.1524)
				)
			)
		)
		(property "Device Type" "C1206H71"
			(at -0.127 -6.6548 90)
			(unlocked yes)
			(layer "F.Fab")
			(hide yes)
			(effects
				(font
					(size 1.016 1.016)
					(thickness 0.1524)
				)
			)
		)
		(duplicate_pad_numbers_are_jumpers no)
		(fp_line
			(start 1.016 -2.2352)
			(end 1.016 -0.8382)
			(stroke
				(width 0.1524)
				(type default)
			)
			(layer "F.SilkS")
		)
		(fp_line
			(start -1.016 -2.2352)
			(end 1.016 -2.2352)
			(stroke
				(width 0.1524)
				(type default)
			)
			(layer "F.SilkS")
		)
		(fp_line
			(start -1.016 -0.8382)
			(end -1.016 -2.2352)
			(stroke
				(width 0.1524)
				(type default)
			)
			(layer "F.SilkS")
		)
		(fp_line
			(start 1.016 0.8382)
			(end 1.016 2.2352)
			(stroke
				(width 0.1524)
				(type default)
			)
			(layer "F.SilkS")
		)
		(fp_line
			(start 1.016 2.2352)
			(end -1.016 2.2352)
			(stroke
				(width 0.1524)
				(type default)
			)
			(layer "F.SilkS")
		)
		(fp_line
			(start -1.016 2.2352)
			(end -1.016 0.8382)
			(stroke
				(width 0.1524)
				(type default)
			)
			(layer "F.SilkS")
		)
		(fp_rect
			(start -1.0922 2.3114)
			(end 1.0922 -2.3114)
			(stroke
				(width 0)
				(type default)
			)
			(fill no)
			(layer "F.CrtYd")
		)
		(fp_poly
			(pts
				(xy 1.0922 -2.3114) (xy 1.0922 2.3114) (xy -1.0922 2.3114) (xy -1.0922 -2.3114)
			)
			(stroke
				(width 0)
				(type default)
			)
			(fill no)
			(layer "F.Fab")
		)
		(pad "1" smd rect
			(at 0 -1.397 90)
			(size 1.651 1.27)
			(layers "F.Cu" "F.Mask" "F.Paste")
			(net "P3V3_STBY")
		)
		(pad "2" smd rect
			(at 0 1.397 90)
			(size 1.651 1.27)
			(layers "F.Cu" "F.Mask" "F.Paste")
			(net "GND")
		)
	)
)
